(kicad_pcb
	(version 20260206)
	(generator "pcbnew")
	(generator_version "10.0")
	(general
		(thickness 1.6)
		(legacy_teardrops no)
	)
	(paper "A4")
	(title_block
		(title "Wiwynn_Tioga_Pass_MB.brd")
		(comment 1 "Tioga Pass / footprints 1563-1568 of 4770")
	)
	(layers
		(0 "F.Cu" signal "TOP")
		(4 "In1.Cu" signal "L2GND")
		(6 "In2.Cu" signal "L3")
		(8 "In3.Cu" signal "L4GND")
		(10 "In4.Cu" signal "L5")
		(12 "In5.Cu" signal "L6GND")
		(14 "In6.Cu" signal "L7VCC")
		(16 "In7.Cu" signal "L8VCC")
		(18 "In8.Cu" signal "L9GND")
		(20 "In9.Cu" signal "L10")
		(22 "In10.Cu" signal "L11GND")
		(24 "In11.Cu" signal "L12")
		(26 "In12.Cu" signal "L13GND")
		(2 "B.Cu" signal "BOTTOM")
		(9 "F.Adhes" user "F.Adhesive")
		(11 "B.Adhes" user "B.Adhesive")
		(13 "F.Paste" user "Package Geometry/Pastemask Top")
		(15 "B.Paste" user "Package Geometry/Pastemask Bottom")
		(5 "F.SilkS" user "Ref Des/Silkscreen Top")
		(7 "B.SilkS" user "Ref Des/Silkscreen Bottom")
		(1 "F.Mask" user "Board Geometry/Soldermask Top")
		(3 "B.Mask" user "Board Geometry/Soldermask Bottom")
		(17 "Dwgs.User" user "User.Drawings")
		(19 "Cmts.User" user "User.Comments")
		(21 "Eco1.User" user "User.Eco1")
		(23 "Eco2.User" user "User.Eco2")
		(25 "Edge.Cuts" user "Board Geometry/Outline")
		(27 "Margin" user)
		(31 "F.CrtYd" user "Package Geometry/Place Bound Top")
		(29 "B.CrtYd" user "Package Geometry/Place Bound Bottom")
		(35 "F.Fab" user "Ref Des/Assembly Top")
		(33 "B.Fab" user "Ref Des/Assembly Bottom")
	)
	(footprint ""
		(layer "F.Cu")
		(at 248.8819 -140.208 -90)
		(property "Reference" "C5A12"
			(at 1.848866 0.752348 270)
			(unlocked yes)
			(layer "F.SilkS")
			(effects
				(font
					(size 1.27 0.9652)
					(thickness 0.1524)
				)
			)
		)
		(property "Value" ""
			(at 0 0 270)
			(layer "F.Fab")
			(effects
				(font
					(size 1.27 1.27)
				)
			)
		)
		(duplicate_pad_numbers_are_jumpers no)
		(fp_rect
			(start -0.500126 1.598422)
			(end 0.500126 -0.201422)
			(stroke
				(width 0)
				(type default)
			)
			(fill no)
			(layer "F.CrtYd")
		)
		(fp_line
			(start -0.500126 1.598422)
			(end -0.500126 -0.201422)
			(stroke
				(width 0.1)
				(type default)
			)
			(layer "F.Fab")
		)
		(fp_line
			(start 0.500126 1.598422)
			(end -0.500126 1.598422)
			(stroke
				(width 0.1)
				(type default)
			)
			(layer "F.Fab")
		)
		(fp_line
			(start -0.500126 -0.201422)
			(end 0.500126 -0.201422)
			(stroke
				(width 0.1)
				(type default)
			)
			(layer "F.Fab")
		)
		(fp_line
			(start 0.500126 -0.201422)
			(end 0.500126 1.598422)
			(stroke
				(width 0.1)
				(type default)
			)
			(layer "F.Fab")
		)
		(pad "1" smd rect
			(at 0 0 180)
			(size 0.889 0.9906)
			(layers "F.Cu" "F.Mask" "F.Paste")
			(net "PVDDQ_DEF")
		)
		(pad "2" smd rect
			(at 0 1.397 180)
			(size 0.889 0.9906)
			(layers "F.Cu" "F.Mask" "F.Paste")
			(net "GND")
		)
		(zone
			(layer "F.Cu")
			(hatch none 0.5)
			(connect_pads
				(clearance 0)
			)
			(min_thickness 0.25)
			(keepout
				(tracks not_allowed)
				(vias allowed)
				(pads allowed)
				(copperpour not_allowed)
				(footprints allowed)
			)
			(placement
				(enabled no)
				(sheetname "")
			)
			(fill
				(thermal_gap 0.5)
				(thermal_bridge_width 0.5)
				(island_removal_mode 0)
			)
			(polygon
				(pts
					(xy 247.9294 -140.7033) (xy 247.9294 -139.7127) (xy 248.4374 -139.7127) (xy 248.4374 -140.7033)
				)
			)
		)
		(zone
			(layer "F.Cu")
			(hatch none 0.5)
			(connect_pads
				(clearance 0)
			)
			(min_thickness 0.25)
			(keepout
				(tracks allowed)
				(vias not_allowed)
				(pads allowed)
				(copperpour not_allowed)
				(footprints allowed)
			)
			(placement
				(enabled no)
				(sheetname "")
			)
			(fill
				(thermal_gap 0.5)
				(thermal_bridge_width 0.5)
				(island_removal_mode 0)
			)
			(polygon
				(pts
					(xy 247.9294 -140.7033) (xy 247.9294 -139.7127) (xy 248.4374 -139.7127) (xy 248.4374 -140.7033)
				)
			)
		)
	)
	(footprint ""
		(layer "F.Cu")
		(at 117.029992 -71.460614 -90)
		(property "Reference" "R3D19"
			(at 0 0 270)
			(layer "F.SilkS")
			(hide yes)
			(effects
				(font
					(size 1.27 1.27)
				)
			)
		)
		(property "Value" ""
			(at 0 0 270)
			(layer "F.Fab")
			(effects
				(font
					(size 1.27 1.27)
				)
			)
		)
		(duplicate_pad_numbers_are_jumpers no)
		(fp_poly
			(pts
				(xy -0.2794 -0.1016) (xy 0.2794 -0.1016) (xy 0.2794 0.9906) (xy -0.2794 0.9906)
			)
			(stroke
				(width 0)
				(type default)
			)
			(fill no)
			(layer "F.CrtYd")
		)
		(fp_line
			(start -0.2794 0.9906)
			(end 0.2794 0.9906)
			(stroke
				(width 0.1)
				(type default)
			)
			(layer "F.Fab")
		)
		(fp_line
			(start 0.2794 0.9906)
			(end 0.2794 -0.1016)
			(stroke
				(width 0.1)
				(type default)
			)
			(layer "F.Fab")
		)
		(fp_line
			(start -0.2794 -0.1016)
			(end -0.2794 0.9906)
			(stroke
				(width 0.1)
				(type default)
			)
			(layer "F.Fab")
		)
		(fp_line
			(start 0.2794 -0.1016)
			(end -0.2794 -0.1016)
			(stroke
				(width 0.1)
				(type default)
			)
			(layer "F.Fab")
		)
		(pad "1" smd rect
			(at 0 0 270)
			(size 0.508 0.508)
			(layers "F.Cu" "F.Mask" "F.Paste")
			(net "A_CPU1_UPI01_RBIAS")
		)
		(pad "2" smd rect
			(at 0 0.889 270)
			(size 0.508 0.508)
			(layers "F.Cu" "F.Mask" "F.Paste")
			(net "GND")
		)
		(zone
			(layer "F.Cu")
			(hatch none 0.5)
			(connect_pads
				(clearance 0)
			)
			(min_thickness 0.25)
			(keepout
				(tracks not_allowed)
				(vias allowed)
				(pads allowed)
				(copperpour not_allowed)
				(footprints allowed)
			)
			(placement
				(enabled no)
				(sheetname "")
			)
			(fill
				(thermal_gap 0.5)
				(thermal_bridge_width 0.5)
				(island_removal_mode 0)
			)
			(polygon
				(pts
					(xy 116.394992 -71.714614) (xy 116.394992 -71.206614) (xy 116.775992 -71.206614) (xy 116.775992 -71.714614)
				)
			)
		)
		(zone
			(layer "F.Cu")
			(hatch none 0.5)
			(connect_pads
				(clearance 0)
			)
			(min_thickness 0.25)
			(keepout
				(tracks allowed)
				(vias not_allowed)
				(pads allowed)
				(copperpour not_allowed)
				(footprints allowed)
			)
			(placement
				(enabled no)
				(sheetname "")
			)
			(fill
				(thermal_gap 0.5)
				(thermal_bridge_width 0.5)
				(island_removal_mode 0)
			)
			(polygon
				(pts
					(xy 116.775992 -71.714614) (xy 116.775992 -71.206614) (xy 116.394992 -71.206614) (xy 116.394992 -71.714614)
				)
			)
		)
	)
	(footprint ""
		(layer "F.Cu")
		(at 39.723568 -102.616 180)
		(property "Reference" "R1C6"
			(at 0 0 180)
			(layer "F.SilkS")
			(hide yes)
			(effects
				(font
					(size 1.27 1.27)
				)
			)
		)
		(property "Value" ""
			(at 0 0 180)
			(layer "F.Fab")
			(effects
				(font
					(size 1.27 1.27)
				)
			)
		)
		(duplicate_pad_numbers_are_jumpers no)
		(fp_poly
			(pts
				(xy -0.2794 -0.1016) (xy 0.2794 -0.1016) (xy 0.2794 0.9906) (xy -0.2794 0.9906)
			)
			(stroke
				(width 0)
				(type default)
			)
			(fill no)
			(layer "F.CrtYd")
		)
		(fp_line
			(start 0.2794 0.9906)
			(end 0.2794 -0.1016)
			(stroke
				(width 0.1)
				(type default)
			)
			(layer "F.Fab")
		)
		(fp_line
			(start 0.2794 -0.1016)
			(end -0.2794 -0.1016)
			(stroke
				(width 0.1)
				(type default)
			)
			(layer "F.Fab")
		)
		(fp_line
			(start -0.2794 0.9906)
			(end 0.2794 0.9906)
			(stroke
				(width 0.1)
				(type default)
			)
			(layer "F.Fab")
		)
		(fp_line
			(start -0.2794 -0.1016)
			(end -0.2794 0.9906)
			(stroke
				(width 0.1)
				(type default)
			)
			(layer "F.Fab")
		)
		(pad "1" smd rect
			(at 0 0 180)
			(size 0.508 0.508)
			(layers "F.Cu" "F.Mask" "F.Paste")
			(net "VSENSE_PVSA_CPU1_P")
		)
		(pad "2" smd rect
			(at 0 0.889 180)
			(size 0.508 0.508)
			(layers "F.Cu" "F.Mask" "F.Paste")
			(net "VSENSE_PVSA_CPU1_N")
		)
		(zone
			(layer "F.Cu")
			(hatch none 0.5)
			(connect_pads
				(clearance 0)
			)
			(min_thickness 0.25)
			(keepout
				(tracks not_allowed)
				(vias allowed)
				(pads allowed)
				(copperpour not_allowed)
				(footprints allowed)
			)
			(placement
				(enabled no)
				(sheetname "")
			)
			(fill
				(thermal_gap 0.5)
				(thermal_bridge_width 0.5)
				(island_removal_mode 0)
			)
			(polygon
				(pts
					(xy 39.977568 -103.251) (xy 39.469568 -103.251) (xy 39.469568 -102.87) (xy 39.977568 -102.87)
				)
			)
		)
		(zone
			(layer "F.Cu")
			(hatch none 0.5)
			(connect_pads
				(clearance 0)
			)
			(min_thickness 0.25)
			(keepout
				(tracks allowed)
				(vias not_allowed)
				(pads allowed)
				(copperpour not_allowed)
				(footprints allowed)
			)
			(placement
				(enabled no)
				(sheetname "")
			)
			(fill
				(thermal_gap 0.5)
				(thermal_bridge_width 0.5)
				(island_removal_mode 0)
			)
			(polygon
				(pts
					(xy 39.977568 -102.87) (xy 39.469568 -102.87) (xy 39.469568 -103.251) (xy 39.977568 -103.251)
				)
			)
		)
	)
	(footprint ""
		(layer "F.Cu")
		(at 149.065488 -164.91712 90)
		(property "Reference" "T1D8"
			(at 0 0 90)
			(layer "F.SilkS")
			(hide yes)
			(effects
				(font
					(size 1.27 1.27)
				)
			)
		)
		(property "Value" "*"
			(at -3.4036 -4.46405 90)
			(unlocked yes)
			(layer "F.Fab")
			(hide yes)
			(effects
				(font
					(size 0.889 0.889)
					(thickness 0.1524)
				)
			)
		)
		(property "Device Type" "TEST-PAD-12P-1-GP-U_DISCRET-GBA"
			(at -3.4036 -5.98805 90)
			(unlocked yes)
			(layer "F.Fab")
			(hide yes)
			(effects
				(font
					(size 0.889 0.889)
					(thickness 0.1524)
				)
			)
		)
		(duplicate_pad_numbers_are_jumpers no)
		(fp_line
			(start 2.3622 -4.826)
			(end 2.3622 3.4798)
			(stroke
				(width 0.1524)
				(type default)
			)
			(layer "F.SilkS")
		)
		(fp_line
			(start -2.3876 -4.826)
			(end 2.3622 -4.826)
			(stroke
				(width 0.1524)
				(type default)
			)
			(layer "F.SilkS")
		)
		(fp_line
			(start 2.3622 3.4798)
			(end -2.3876 3.4798)
			(stroke
				(width 0.1524)
				(type default)
			)
			(layer "F.SilkS")
		)
		(fp_line
			(start -2.3876 3.4798)
			(end -2.3876 -4.826)
			(stroke
				(width 0.1524)
				(type default)
			)
			(layer "F.SilkS")
		)
		(fp_rect
			(start -2.6416 3.7338)
			(end 2.6162 -5.08)
			(stroke
				(width 0)
				(type default)
			)
			(fill no)
			(layer "F.CrtYd")
		)
		(fp_rect
			(start -2.6416 3.7338)
			(end 2.6162 -5.08)
			(stroke
				(width 0)
				(type default)
			)
			(fill no)
			(layer "F.Fab")
		)
		(pad "1" smd circle
			(at 0.496824 -1.301496 90)
			(size 0.6604 0.6604)
			(layers "F.Cu" "F.Mask" "F.Paste")
			(net "L10_85OHM_5INCH_DN")
		)
		(pad "2" smd circle
			(at -0.503936 -1.301496 90)
			(size 0.6604 0.6604)
			(layers "F.Cu" "F.Mask" "F.Paste")
			(net "L10_85OHM_5INCH_DP")
		)
		(pad "3" smd custom
			(at -0.00889 0.370078 90)
			(size 0.74295 0.74295)
			(layers "F.Cu" "F.Mask" "F.Paste")
			(net "GND")
			(options
				(clearance outline)
				(anchor circle)
			)
			(primitives
				(gr_poly
					(pts
						(xy -2.1209 1.4859) (xy 2.1209 1.4859) (xy 2.1209 -1.4859) (xy 1.08585 -1.4859) (xy 1.08585 -0.4699)
						(xy -1.08585 -0.4699) (xy -1.08585 -1.4859) (xy -2.1209 -1.4859)
					)
					(width 0)
					(fill yes)
				)
			)
		)
		(pad "4" thru_hole circle
			(at 1.266444 -3.851656 90)
			(size 1.4478 1.4478)
			(drill 1.0414)
			(layers "*.Cu" "*.Mask")
			(remove_unused_layers no)
			(net "GND")
			(clearance 0.1524)
			(thermal_gap 0.1524)
		)
		(pad "5" thru_hole circle
			(at -1.273556 -3.851656 90)
			(size 1.4478 1.4478)
			(drill 1.0414)
			(layers "*.Cu" "*.Mask")
			(remove_unused_layers no)
			(net "GND")
			(clearance 0.1524)
			(thermal_gap 0.1524)
		)
		(pad "6" thru_hole circle
			(at 1.266444 2.498344 90)
			(size 1.4478 1.4478)
			(drill 1.0414)
			(layers "*.Cu" "*.Mask")
			(remove_unused_layers no)
			(net "GND")
			(clearance 0.1524)
			(thermal_gap 0.1524)
		)
		(pad "7" thru_hole circle
			(at -1.273556 2.498344 90)
			(size 1.4478 1.4478)
			(drill 1.0414)
			(layers "*.Cu" "*.Mask")
			(remove_unused_layers no)
			(net "GND")
			(clearance 0.1524)
			(thermal_gap 0.1524)
		)
		(pad "8" thru_hole circle
			(at 1.27 -0.4572 90)
			(size 0.7112 0.7112)
			(drill 0.4064)
			(layers "*.Cu" "*.Mask")
			(remove_unused_layers no)
			(net "GND")
			(clearance 0.1016)
			(thermal_gap 0.1016)
		)
		(pad "9" thru_hole circle
			(at 1.27 0.762 90)
			(size 0.7112 0.7112)
			(drill 0.4064)
			(layers "*.Cu" "*.Mask")
			(remove_unused_layers no)
			(net "GND")
			(clearance 0.1016)
			(thermal_gap 0.1016)
		)
		(pad "10" thru_hole circle
			(at -0.0254 0.762 90)
			(size 0.7112 0.7112)
			(drill 0.4064)
			(layers "*.Cu" "*.Mask")
			(remove_unused_layers no)
			(net "GND")
			(clearance 0.1016)
			(thermal_gap 0.1016)
		)
		(pad "11" thru_hole circle
			(at -1.27 0.762 90)
			(size 0.7112 0.7112)
			(drill 0.4064)
			(layers "*.Cu" "*.Mask")
			(remove_unused_layers no)
			(net "GND")
			(clearance 0.1016)
			(thermal_gap 0.1016)
		)
		(pad "12" thru_hole circle
			(at -1.27 -0.4572 90)
			(size 0.7112 0.7112)
			(drill 0.4064)
			(layers "*.Cu" "*.Mask")
			(remove_unused_layers no)
			(net "GND")
			(clearance 0.1016)
			(thermal_gap 0.1016)
		)
	)
	(footprint ""
		(layer "F.Cu")
		(at 17.399 -84.455 -90)
		(property "Reference" "Q1D1"
			(at 2.94767 1.905 0)
			(unlocked yes)
			(layer "F.SilkS")
			(effects
				(font
					(size 0.7874 0.5842)
					(thickness 0.1524)
				)
				(justify left)
			)
		)
		(property "Value" ""
			(at 0 0 270)
			(layer "F.Fab")
			(effects
				(font
					(size 1.27 1.27)
				)
			)
		)
		(duplicate_pad_numbers_are_jumpers no)
		(fp_circle
			(center -0.848614 -0.6477)
			(end -0.848614 -0.7747)
			(stroke
				(width 0.254)
				(type default)
			)
			(fill no)
			(layer "F.SilkS")
		)
		(fp_poly
			(pts
				(xy 0.21463 -0.450088) (xy 1.56337 -0.450088) (xy 1.56337 1.75006) (xy 0.21463 1.75006)
			)
			(stroke
				(width 0)
				(type default)
			)
			(fill no)
			(layer "F.CrtYd")
		)
		(fp_line
			(start 0.21463 1.75006)
			(end 0.21463 -0.450088)
			(stroke
				(width 0.1)
				(type default)
			)
			(layer "F.Fab")
		)
		(fp_line
			(start 1.56337 1.75006)
			(end 0.21463 1.75006)
			(stroke
				(width 0.1)
				(type default)
			)
			(layer "F.Fab")
		)
		(fp_line
			(start 0.21463 -0.450088)
			(end 1.56337 -0.450088)
			(stroke
				(width 0.1)
				(type default)
			)
			(layer "F.Fab")
		)
		(fp_line
			(start 1.56337 -0.450088)
			(end 1.56337 1.75006)
			(stroke
				(width 0.1)
				(type default)
			)
			(layer "F.Fab")
		)
		(fp_circle
			(center -0.848614 -0.6477)
			(end -0.848614 -0.7747)
			(stroke
				(width 0.254)
				(type default)
			)
			(fill no)
			(layer "F.Fab")
		)
		(pad "1" smd rect
			(at 0 0 270)
			(size 1.016 0.381)
			(layers "F.Cu" "F.Mask" "F.Paste")
			(net "AGND_HSC")
		)
		(pad "2" smd rect
			(at 0 0.649986 270)
			(size 1.016 0.381)
			(layers "F.Cu" "F.Mask" "F.Paste")
			(net "A_HSC_LOW_EN")
		)
		(pad "3" smd rect
			(at 0 1.299972 270)
			(size 1.016 0.381)
			(layers "F.Cu" "F.Mask" "F.Paste")
			(net "A_HSC_ISET_S")
		)
		(pad "4" smd rect
			(at 1.778 1.299972 270)
			(size 1.016 0.381)
			(layers "F.Cu" "F.Mask" "F.Paste")
			(net "AGND_HSC")
		)
		(pad "5" smd rect
			(at 1.778 0.649986 270)
			(size 1.016 0.381)
			(layers "F.Cu" "F.Mask" "F.Paste")
			(net "A_HSC_HIGH_EN")
		)
		(pad "6" smd rect
			(at 1.778 0 270)
			(size 1.016 0.381)
			(layers "F.Cu" "F.Mask" "F.Paste")
			(net "A_HSC_ISET_S2")
		)
	)
	(footprint ""
		(layer "F.Cu")
		(at 393.674346 -64.172338 -90)
		(property "Reference" "C8F1"
			(at 0 0 270)
			(layer "F.SilkS")
			(hide yes)
			(effects
				(font
					(size 1.27 1.27)
				)
			)
		)
		(property "Value" ""
			(at 0 0 270)
			(layer "F.Fab")
			(effects
				(font
					(size 1.27 1.27)
				)
			)
		)
		(duplicate_pad_numbers_are_jumpers no)
		(fp_poly
			(pts
				(xy 0.3048 -0.1016) (xy 0.3048 0.9906) (xy -0.3048 0.9906) (xy -0.3048 -0.1016)
			)
			(stroke
				(width 0)
				(type default)
			)
			(fill no)
			(layer "F.CrtYd")
		)
		(fp_line
			(start -0.3048 0.9906)
			(end 0.3048 0.9906)
			(stroke
				(width 0.1)
				(type default)
			)
			(layer "F.Fab")
		)
		(fp_line
			(start 0.3048 0.9906)
			(end 0.3048 -0.1016)
			(stroke
				(width 0.1)
				(type default)
			)
			(layer "F.Fab")
		)
		(fp_line
			(start -0.3048 -0.1016)
			(end -0.3048 0.9906)
			(stroke
				(width 0.1)
				(type default)
			)
			(layer "F.Fab")
		)
		(fp_line
			(start 0.3048 -0.1016)
			(end -0.3048 -0.1016)
			(stroke
				(width 0.1)
				(type default)
			)
			(layer "F.Fab")
		)
		(pad "1" smd rect
			(at 0 0 270)
			(size 0.508 0.508)
			(layers "F.Cu" "F.Mask" "F.Paste")
			(net "VR_P5V_STBY_RC_COMP")
		)
		(pad "2" smd rect
			(at 0 0.889 270)
			(size 0.508 0.508)
			(layers "F.Cu" "F.Mask" "F.Paste")
			(net "AGND_P5V_STBY")
		)
		(zone
			(layer "F.Cu")
			(hatch none 0.5)
			(connect_pads
				(clearance 0)
			)
			(min_thickness 0.25)
			(keepout
				(tracks not_allowed)
				(vias allowed)
				(pads allowed)
				(copperpour not_allowed)
				(footprints allowed)
			)
			(placement
				(enabled no)
				(sheetname "")
			)
			(fill
				(thermal_gap 0.5)
				(thermal_bridge_width 0.5)
				(island_removal_mode 0)
			)
			(polygon
				(pts
					(xy 393.039346 -64.426338) (xy 393.039346 -63.918338) (xy 393.420346 -63.918338) (xy 393.420346 -64.426338)
				)
			)
		)
		(zone
			(layer "F.Cu")
			(hatch none 0.5)
			(connect_pads
				(clearance 0)
			)
			(min_thickness 0.25)
			(keepout
				(tracks allowed)
				(vias not_allowed)
				(pads allowed)
				(copperpour not_allowed)
				(footprints allowed)
			)
			(placement
				(enabled no)
				(sheetname "")
			)
			(fill
				(thermal_gap 0.5)
				(thermal_bridge_width 0.5)
				(island_removal_mode 0)
			)
			(polygon
				(pts
					(xy 393.420346 -64.426338) (xy 393.420346 -63.918338) (xy 393.039346 -63.918338) (xy 393.039346 -64.426338)
				)
			)
		)
	)
)
